# T6G (Grand Teton) — schematic netlist excerpt (pin names and nets, part order shuffled) for the footprints in the layout excerpt that follows; sources: Cadence DE-HDL packaged netlist, KiCad conversion of 04192023_DAF0TMB3IC0_F0TG_MB_C_brd_V02_OCP.brd

PC170  Q_CAP  560PF 50V 10% EMPTY  pkg C0402  page 211 : A = SW_PVDDCR_CPU0_P1_SW1 ; B = SW_PVDDCR_CPU0_P1_SW1_RC
C8362  Q_CAP  1000PF 50V 5% EMPTY  pkg 0402  page 217 : A = PWRGD_PVDDIO_P1_R ; B = GND

(kicad_pcb
	(version 20260206)
	(generator "pcbnew")
	(generator_version "10.0")
	(general
		(thickness 1.6)
		(legacy_teardrops no)
	)
	(paper "A4")
	(title_block
		(title "04192023_DAF0TMB3IC0_F0TG_MB_C_brd_V02_OCP.brd")
		(comment 1 "Grand Teton / footprints 736-737 of 8354")
	)
	(layers
		(0 "F.Cu" signal "TOP")
		(4 "In1.Cu" signal "GND")
		(6 "In2.Cu" signal "IN1")
		(8 "In3.Cu" signal "GND1")
		(10 "In4.Cu" signal "IN2")
		(12 "In5.Cu" signal "GND2")
		(14 "In6.Cu" signal "IN3")
		(16 "In7.Cu" signal "GND3")
		(18 "In8.Cu" signal "VCC")
		(20 "In9.Cu" signal "VCC1")
		(22 "In10.Cu" signal "GND4")
		(24 "In11.Cu" signal "IN4")
		(26 "In12.Cu" signal "GND5")
		(28 "In13.Cu" signal "IN5")
		(30 "In14.Cu" signal "GND6")
		(32 "In15.Cu" signal "IN6")
		(34 "In16.Cu" signal "GND7")
		(2 "B.Cu" signal "BOTTOM")
		(9 "F.Adhes" user "F.Adhesive")
		(11 "B.Adhes" user "B.Adhesive")
		(13 "F.Paste" user "Package Geometry/Pastemask Top")
		(15 "B.Paste" user "Package Geometry/Pastemask Bottom")
		(5 "F.SilkS" user "Ref Des/Silkscreen Top")
		(7 "B.SilkS" user "Ref Des/Silkscreen Bottom")
		(1 "F.Mask" user "Board Geometry/Soldermask Top")
		(3 "B.Mask" user "Board Geometry/Soldermask Bottom")
		(17 "Dwgs.User" user "User.Drawings")
		(19 "Cmts.User" user "User.Comments")
		(21 "Eco1.User" user "User.Eco1")
		(23 "Eco2.User" user "User.Eco2")
		(25 "Edge.Cuts" user "Board Geometry/Outline")
		(27 "Margin" user)
		(31 "F.CrtYd" user "Package Geometry/Place Bound Top")
		(29 "B.CrtYd" user "Package Geometry/Place Bound Bottom")
		(35 "F.Fab" user "Ref Des/Assembly Top")
		(33 "B.Fab" user "Ref Des/Assembly Bottom")
	)
	(footprint ""
		(layer "F.Cu")
		(at 85.978492 -185.748168)
		(property "Reference" "PC170"
			(at 0 0 0)
			(layer "F.SilkS")
			(hide yes)
			(effects
				(font
					(size 1.27 1.27)
				)
			)
		)
		(property "Value" ""
			(at 0 0 0)
			(layer "F.Fab")
			(effects
				(font
					(size 1.27 1.27)
				)
			)
		)
		(duplicate_pad_numbers_are_jumpers no)
		(fp_line
			(start -0.7874 -0.4064)
			(end 0.7874 -0.4064)
			(stroke
				(width 0.1524)
				(type default)
			)
			(layer "F.SilkS")
		)
		(fp_line
			(start -0.7874 0.4064)
			(end -0.7874 -0.4064)
			(stroke
				(width 0.1524)
				(type default)
			)
			(layer "F.SilkS")
		)
		(fp_line
			(start 0.7874 -0.4064)
			(end 0.7874 0.4064)
			(stroke
				(width 0.1524)
				(type default)
			)
			(layer "F.SilkS")
		)
		(fp_line
			(start 0.7874 0.4064)
			(end -0.7874 0.4064)
			(stroke
				(width 0.1524)
				(type default)
			)
			(layer "F.SilkS")
		)
		(fp_line
			(start -0.67945 -0.305054)
			(end -0.12065 -0.305054)
			(stroke
				(width 0.1)
				(type default)
			)
			(layer "F.Fab")
		)
		(fp_line
			(start -0.67945 0.3048)
			(end -0.67945 -0.305054)
			(stroke
				(width 0.1)
				(type default)
			)
			(layer "F.Fab")
		)
		(fp_line
			(start -0.12065 -0.305054)
			(end -0.12065 -0.2794)
			(stroke
				(width 0.1)
				(type default)
			)
			(layer "F.Fab")
		)
		(fp_line
			(start -0.12065 -0.2794)
			(end 0.12065 -0.2794)
			(stroke
				(width 0.1)
				(type default)
			)
			(layer "F.Fab")
		)
		(fp_line
			(start -0.12065 0.2794)
			(end -0.12065 0.3048)
			(stroke
				(width 0.1)
				(type default)
			)
			(layer "F.Fab")
		)
		(fp_line
			(start -0.12065 0.3048)
			(end -0.67945 0.3048)
			(stroke
				(width 0.1)
				(type default)
			)
			(layer "F.Fab")
		)
		(fp_line
			(start 0.120396 0.2794)
			(end -0.12065 0.2794)
			(stroke
				(width 0.1)
				(type default)
			)
			(layer "F.Fab")
		)
		(fp_line
			(start 0.120396 0.3048)
			(end 0.120396 0.2794)
			(stroke
				(width 0.1)
				(type default)
			)
			(layer "F.Fab")
		)
		(fp_line
			(start 0.12065 -0.3048)
			(end 0.67945 -0.3048)
			(stroke
				(width 0.1)
				(type default)
			)
			(layer "F.Fab")
		)
		(fp_line
			(start 0.12065 -0.2794)
			(end 0.12065 -0.3048)
			(stroke
				(width 0.1)
				(type default)
			)
			(layer "F.Fab")
		)
		(fp_line
			(start 0.67945 -0.3048)
			(end 0.67945 0.3048)
			(stroke
				(width 0.1)
				(type default)
			)
			(layer "F.Fab")
		)
		(fp_line
			(start 0.67945 0.3048)
			(end 0.120396 0.3048)
			(stroke
				(width 0.1)
				(type default)
			)
			(layer "F.Fab")
		)
		(pad "1" smd circle
			(at -0.40005 0)
			(size 0 0)
			(layers "F.Cu" "F.Mask" "F.Paste")
			(net "SW_PVDDCR_CPU0_P1_SW1")
		)
		(pad "2" smd circle
			(at 0.40005 0)
			(size 0 0)
			(layers "F.Cu" "F.Mask" "F.Paste")
			(net "SW_PVDDCR_CPU0_P1_SW1_RC")
		)
	)
	(footprint ""
		(layer "F.Cu")
		(at 24.765 -362.204 180)
		(property "Reference" "C8362"
			(at 0 0 180)
			(layer "F.SilkS")
			(hide yes)
			(effects
				(font
					(size 1.27 1.27)
				)
			)
		)
		(property "Value" ""
			(at 0 0 180)
			(layer "F.Fab")
			(effects
				(font
					(size 1.27 1.27)
				)
			)
		)
		(duplicate_pad_numbers_are_jumpers no)
		(fp_line
			(start 0.7874 0.4064)
			(end -0.7874 0.4064)
			(stroke
				(width 0.1524)
				(type default)
			)
			(layer "F.SilkS")
		)
		(fp_line
			(start 0.7874 -0.4064)
			(end 0.7874 0.4064)
			(stroke
				(width 0.1524)
				(type default)
			)
			(layer "F.SilkS")
		)
		(fp_line
			(start -0.7874 0.4064)
			(end -0.7874 -0.4064)
			(stroke
				(width 0.1524)
				(type default)
			)
			(layer "F.SilkS")
		)
		(fp_line
			(start -0.7874 -0.4064)
			(end 0.7874 -0.4064)
			(stroke
				(width 0.1524)
				(type default)
			)
			(layer "F.SilkS")
		)
		(fp_line
			(start 0.67945 0.3048)
			(end 0.120396 0.3048)
			(stroke
				(width 0.1)
				(type default)
			)
			(layer "F.Fab")
		)
		(fp_line
			(start 0.67945 -0.3048)
			(end 0.67945 0.3048)
			(stroke
				(width 0.1)
				(type default)
			)
			(layer "F.Fab")
		)
		(fp_line
			(start 0.12065 -0.2794)
			(end 0.12065 -0.3048)
			(stroke
				(width 0.1)
				(type default)
			)
			(layer "F.Fab")
		)
		(fp_line
			(start 0.12065 -0.3048)
			(end 0.67945 -0.3048)
			(stroke
				(width 0.1)
				(type default)
			)
			(layer "F.Fab")
		)
		(fp_line
			(start 0.120396 0.3048)
			(end 0.120396 0.2794)
			(stroke
				(width 0.1)
				(type default)
			)
			(layer "F.Fab")
		)
		(fp_line
			(start 0.120396 0.2794)
			(end -0.12065 0.2794)
			(stroke
				(width 0.1)
				(type default)
			)
			(layer "F.Fab")
		)
		(fp_line
			(start -0.12065 0.3048)
			(end -0.67945 0.3048)
			(stroke
				(width 0.1)
				(type default)
			)
			(layer "F.Fab")
		)
		(fp_line
			(start -0.12065 0.2794)
			(end -0.12065 0.3048)
			(stroke
				(width 0.1)
				(type default)
			)
			(layer "F.Fab")
		)
		(fp_line
			(start -0.12065 -0.2794)
			(end 0.12065 -0.2794)
			(stroke
				(width 0.1)
				(type default)
			)
			(layer "F.Fab")
		)
		(fp_line
			(start -0.12065 -0.305054)
			(end -0.12065 -0.2794)
			(stroke
				(width 0.1)
				(type default)
			)
			(layer "F.Fab")
		)
		(fp_line
			(start -0.67945 0.3048)
			(end -0.67945 -0.305054)
			(stroke
				(width 0.1)
				(type default)
			)
			(layer "F.Fab")
		)
		(fp_line
			(start -0.67945 -0.305054)
			(end -0.12065 -0.305054)
			(stroke
				(width 0.1)
				(type default)
			)
			(layer "F.Fab")
		)
		(pad "1" smd circle
			(at -0.40005 0 180)
			(size 0 0)
			(layers "F.Cu" "F.Mask" "F.Paste")
			(net "PWRGD_PVDDIO_P1_R")
		)
		(pad "2" smd circle
			(at 0.40005 0 180)
			(size 0 0)
			(layers "F.Cu" "F.Mask" "F.Paste")
			(net "GND")
		)
	)
)
